(kicad_pcb
	(version 20241229)
	(generator "pcbnew")
	(generator_version "9.0")
	(general
		(thickness 1.552)
		(legacy_teardrops no)
	)
	(paper "A4")
	(title_block
		(date "2023-07-25")
		(rev "1.1.4")
		(comment 9 "footprint 14 of 379 (U11), pads 1-81 of 256")
	)
	(layers
		(0 "F.Cu" signal)
		(4 "In1.Cu" signal)
		(6 "In2.Cu" signal)
		(8 "In3.Cu" signal)
		(10 "In4.Cu" signal)
		(12 "In5.Cu" signal)
		(14 "In6.Cu" signal)
		(2 "B.Cu" signal)
		(9 "F.Adhes" user "F.Adhesive")
		(11 "B.Adhes" user "B.Adhesive")
		(13 "F.Paste" user)
		(15 "B.Paste" user)
		(5 "F.SilkS" user "F.Silkscreen")
		(7 "B.SilkS" user "B.Silkscreen")
		(1 "F.Mask" user)
		(3 "B.Mask" user)
		(17 "Dwgs.User" user "User.Drawings")
		(19 "Cmts.User" user "User.Comments")
		(21 "Eco1.User" user "User.Eco1")
		(23 "Eco2.User" user "User.Eco2")
		(25 "Edge.Cuts" user)
		(27 "Margin" user)
		(31 "F.CrtYd" user "F.Courtyard")
		(29 "B.CrtYd" user "B.Courtyard")
		(35 "F.Fab" user)
		(33 "B.Fab" user)
	)
	(footprint "antmicro-footprints:BGA-256_14x14mm_Layout16x16_P0.8mm"
		(locked yes)
		(layer "F.Cu")
		(at 126.3 90.3 180)
		(property "Reference" "U11"
			(at 0 -8 180)
			(layer "F.SilkS")
			(effects
				(font
					(size 0.7 0.7)
					(thickness 0.15)
				)
				(justify left bottom)
			)
		)
		(property "Value" "LIFCL-40-9BG256C"
			(at -8 8.55 180)
			(layer "F.Fab")
			(effects
				(font
					(size 0.7 0.7)
					(thickness 0.15)
				)
				(justify left bottom)
			)
		)
		(property "Datasheet" "https://www.latticesemi.com/-/media/LatticeSemi/Documents/DataSheets/CrossLink/FPGA-DS-02007-2-1-CrossLink-Family-Data-Sheet.ashx?document_id=51662"
			(at 0 0 180)
			(layer "F.Fab")
			(hide yes)
			(effects
				(font
					(size 1.27 1.27)
					(thickness 0.15)
				)
			)
		)
		(property "Description" "CrossLink-NX™ Field Programmable Gate Array 256-LFBGA"
			(at 0 0 180)
			(layer "F.Fab")
			(hide yes)
			(effects
				(font
					(size 1.27 1.27)
					(thickness 0.15)
				)
			)
		)
		(property "Author" "Antmicro"
			(at 252.6 180.6 0)
			(layer "F.Fab")
			(hide yes)
			(effects
				(font
					(size 1 1)
					(thickness 0.15)
				)
			)
		)
		(property "License" "Apache-2.0"
			(at 252.6 180.6 0)
			(layer "F.Fab")
			(hide yes)
			(effects
				(font
					(size 1 1)
					(thickness 0.15)
				)
			)
		)
		(property "MPN" "LIFCL-40-9BG256C"
			(at 252.6 180.6 0)
			(layer "F.Fab")
			(hide yes)
			(effects
				(font
					(size 1 1)
					(thickness 0.15)
				)
			)
		)
		(property "Manufacturer" "Lattice Semiconductor"
			(at 252.6 180.6 0)
			(layer "F.Fab")
			(hide yes)
			(effects
				(font
					(size 1 1)
					(thickness 0.15)
				)
			)
		)
		(sheetname "/DDR3/")
		(sheetfile "ddr3.kicad_sch")
		(attr smd)
		(pad "A1" smd circle
			(at -6 -6 180)
			(size 0.45 0.45)
			(layers "F.Cu" "F.Mask" "F.Paste")
			(net 1 "GND")
			(pinfunction "VSSADPHY")
			(pintype "power_in")
		)
		(pad "A2" smd circle
			(at -5.2 -6 180)
			(size 0.45 0.45)
			(layers "F.Cu" "F.Mask" "F.Paste")
			(net 13 "/FPGA Power/VCC_PLLDPHY")
			(pinfunction "VCCPLLDPHY0")
			(pintype "power_in")
		)
		(pad "A3" smd circle
			(at -4.4 -6 180)
			(size 0.45 0.45)
			(layers "F.Cu" "F.Mask" "F.Paste")
			(net 116 "/Peripherals/MIPI1_D2_P")
			(pinfunction "DPHY1_D2+")
			(pintype "bidirectional")
		)
		(pad "A4" smd circle
			(at -3.6 -6 180)
			(size 0.45 0.45)
			(layers "F.Cu" "F.Mask" "F.Paste")
			(net 112 "/Peripherals/MIPI1_D0_P")
			(pinfunction "DPHY1_D0+")
			(pintype "bidirectional")
		)
		(pad "A5" smd circle
			(at -2.8 -6 180)
			(size 0.45 0.45)
			(layers "F.Cu" "F.Mask" "F.Paste")
			(net 110 "/Peripherals/MIPI1_CLK_P")
			(pinfunction "DPHY1_CK+")
			(pintype "bidirectional")
		)
		(pad "A6" smd circle
			(at -2 -6 180)
			(size 0.45 0.45)
			(layers "F.Cu" "F.Mask" "F.Paste")
			(net 114 "/Peripherals/MIPI1_D1_P")
			(pinfunction "DPHY1_D1+")
			(pintype "bidirectional")
		)
		(pad "A7" smd circle
			(at -1.2 -6 180)
			(size 0.45 0.45)
			(layers "F.Cu" "F.Mask" "F.Paste")
			(net 118 "/Peripherals/MIPI1_D3_P")
			(pinfunction "DPHY1_D3+")
			(pintype "bidirectional")
		)
		(pad "A8" smd circle
			(at -0.4 -6 180)
			(size 0.45 0.45)
			(layers "F.Cu" "F.Mask" "F.Paste")
			(net 1 "GND")
			(pinfunction "VSSADPHY")
			(pintype "passive")
		)
		(pad "A9" smd circle
			(at 0.4 -6 180)
			(size 0.45 0.45)
			(layers "F.Cu" "F.Mask" "F.Paste")
			(net 1 "GND")
			(pinfunction "SD_REFCLK+")
			(pintype "bidirectional")
		)
		(pad "A10" smd circle
			(at 1.2 -6 180)
			(size 0.45 0.45)
			(layers "F.Cu" "F.Mask" "F.Paste")
			(net 1 "GND")
			(pinfunction "VSSSD")
			(pintype "power_in")
		)
		(pad "A11" smd circle
			(at 2 -6 180)
			(size 0.45 0.45)
			(layers "F.Cu" "F.Mask" "F.Paste")
			(net 383 "unconnected-(U11L-SD0_TXD--PadA11)")
			(pinfunction "SD0_TXD-")
			(pintype "output+no_connect")
		)
		(pad "A12" smd circle
			(at 2.8 -6 180)
			(size 0.45 0.45)
			(layers "F.Cu" "F.Mask" "F.Paste")
			(net 384 "unconnected-(U11L-SD0_TXD+-PadA12)")
			(pinfunction "SD0_TXD+")
			(pintype "output+no_connect")
		)
		(pad "A13" smd circle
			(at 3.6 -6 180)
			(size 0.45 0.45)
			(layers "F.Cu" "F.Mask" "F.Paste")
			(net 1 "GND")
			(pinfunction "VSSSD")
			(pintype "passive")
		)
		(pad "A14" smd circle
			(at 4.4 -6 180)
			(size 0.45 0.45)
			(layers "F.Cu" "F.Mask" "F.Paste")
			(net 1 "GND")
			(pinfunction "SD0_RXD-")
			(pintype "input")
		)
		(pad "A15" smd circle
			(at 5.2 -6 180)
			(size 0.45 0.45)
			(layers "F.Cu" "F.Mask" "F.Paste")
			(net 1 "GND")
			(pinfunction "SD0_RXD+")
			(pintype "input")
		)
		(pad "A16" smd circle
			(at 6 -6 180)
			(size 0.45 0.45)
			(layers "F.Cu" "F.Mask" "F.Paste")
			(net 1 "GND")
			(pinfunction "VSSSD")
			(pintype "passive")
		)
		(pad "B1" smd circle
			(at -6 -5.2 180)
			(size 0.45 0.45)
			(layers "F.Cu" "F.Mask" "F.Paste")
			(net 69 "/Peripherals/MIPI0_D3_P")
			(pinfunction "DPHY0_D3+")
			(pintype "bidirectional")
		)
		(pad "B2" smd circle
			(at -5.2 -5.2 180)
			(size 0.45 0.45)
			(layers "F.Cu" "F.Mask" "F.Paste")
			(net 68 "/Peripherals/MIPI0_D3_N")
			(pinfunction "DPHY0_D3-")
			(pintype "bidirectional")
		)
		(pad "B3" smd circle
			(at -4.4 -5.2 180)
			(size 0.45 0.45)
			(layers "F.Cu" "F.Mask" "F.Paste")
			(net 117 "/Peripherals/MIPI1_D2_N")
			(pinfunction "DPHY1_D2-")
			(pintype "bidirectional")
		)
		(pad "B4" smd circle
			(at -3.6 -5.2 180)
			(size 0.45 0.45)
			(layers "F.Cu" "F.Mask" "F.Paste")
			(net 113 "/Peripherals/MIPI1_D0_N")
			(pinfunction "DPHY1_D0-")
			(pintype "bidirectional")
		)
		(pad "B5" smd circle
			(at -2.8 -5.2 180)
			(size 0.45 0.45)
			(layers "F.Cu" "F.Mask" "F.Paste")
			(net 111 "/Peripherals/MIPI1_CLK_N")
			(pinfunction "DPHY1_CK-")
			(pintype "bidirectional")
		)
		(pad "B6" smd circle
			(at -2 -5.2 180)
			(size 0.45 0.45)
			(layers "F.Cu" "F.Mask" "F.Paste")
			(net 115 "/Peripherals/MIPI1_D1_N")
			(pinfunction "DPHY1_D1-")
			(pintype "bidirectional")
		)
		(pad "B7" smd circle
			(at -1.2 -5.2 180)
			(size 0.45 0.45)
			(layers "F.Cu" "F.Mask" "F.Paste")
			(net 119 "/Peripherals/MIPI1_D3_N")
			(pinfunction "DPHY1_D3-")
			(pintype "bidirectional")
		)
		(pad "B8" smd circle
			(at -0.4 -5.2 180)
			(size 0.45 0.45)
			(layers "F.Cu" "F.Mask" "F.Paste")
			(net 1 "GND")
			(pinfunction "VSSADPHY")
			(pintype "passive")
		)
		(pad "B9" smd circle
			(at 0.4 -5.2 180)
			(size 0.45 0.45)
			(layers "F.Cu" "F.Mask" "F.Paste")
			(net 1 "GND")
			(pinfunction "SD_REFCLK-")
			(pintype "bidirectional")
		)
		(pad "B10" smd circle
			(at 1.2 -5.2 180)
			(size 0.45 0.45)
			(layers "F.Cu" "F.Mask" "F.Paste")
			(net 1 "GND")
			(pinfunction "VSSSD")
			(pintype "passive")
		)
		(pad "B11" smd circle
			(at 2 -5.2 180)
			(size 0.45 0.45)
			(layers "F.Cu" "F.Mask" "F.Paste")
			(net 385 "unconnected-(U11M-VCCAUXSD-PadB11)")
			(pinfunction "VCCAUXSD")
			(pintype "power_in+no_connect")
		)
		(pad "B12" smd circle
			(at 2.8 -5.2 180)
			(size 0.45 0.45)
			(layers "F.Cu" "F.Mask" "F.Paste")
			(net 386 "unconnected-(U11L-SD0_REFRET-PadB12)")
			(pinfunction "SD0_REFRET")
			(pintype "input+no_connect")
		)
		(pad "B13" smd circle
			(at 3.6 -5.2 180)
			(size 0.45 0.45)
			(layers "F.Cu" "F.Mask" "F.Paste")
			(net 387 "unconnected-(U11M-VCCPLLSD0-PadB13)")
			(pinfunction "VCCPLLSD0")
			(pintype "power_in+no_connect")
		)
		(pad "B14" smd circle
			(at 4.4 -5.2 180)
			(size 0.45 0.45)
			(layers "F.Cu" "F.Mask" "F.Paste")
			(net 1 "GND")
			(pinfunction "VSSSD")
			(pintype "passive")
		)
		(pad "B15" smd circle
			(at 5.2 -5.2 180)
			(size 0.45 0.45)
			(layers "F.Cu" "F.Mask" "F.Paste")
			(net 388 "unconnected-(U11M-VCCSD0-PadB15)")
			(pinfunction "VCCSD0")
			(pintype "power_in+no_connect")
		)
		(pad "B16" smd circle
			(at 6 -5.2 180)
			(size 0.45 0.45)
			(layers "F.Cu" "F.Mask" "F.Paste")
			(net 40 "/FPGA/DONE")
			(pinfunction "PT76B/DONE\n")
			(pintype "bidirectional")
		)
		(pad "C1" smd circle
			(at -6 -4.4 180)
			(size 0.45 0.45)
			(layers "F.Cu" "F.Mask" "F.Paste")
			(net 73 "/Peripherals/MIPI0_D1_P")
			(pinfunction "DPHY0_D1+")
			(pintype "bidirectional")
		)
		(pad "C2" smd circle
			(at -5.2 -4.4 180)
			(size 0.45 0.45)
			(layers "F.Cu" "F.Mask" "F.Paste")
			(net 72 "/Peripherals/MIPI0_D1_N")
			(pinfunction "DPHY0_D1-")
			(pintype "bidirectional")
		)
		(pad "C3" smd circle
			(at -4.4 -4.4 180)
			(size 0.45 0.45)
			(layers "F.Cu" "F.Mask" "F.Paste")
			(net 1 "GND")
			(pinfunction "VSSADPHY")
			(pintype "passive")
		)
		(pad "C4" smd circle
			(at -3.6 -4.4 180)
			(size 0.45 0.45)
			(layers "F.Cu" "F.Mask" "F.Paste")
			(net 11 "/FPGA Power/VCC_DPHY")
			(pinfunction "VCCDPHY0")
			(pintype "power_in")
		)
		(pad "C5" smd circle
			(at -2.8 -4.4 180)
			(size 0.45 0.45)
			(layers "F.Cu" "F.Mask" "F.Paste")
			(net 13 "/FPGA Power/VCC_PLLDPHY")
			(pinfunction "VCCPLLDPHY1")
			(pintype "power_in")
		)
		(pad "C6" smd circle
			(at -2 -4.4 180)
			(size 0.45 0.45)
			(layers "F.Cu" "F.Mask" "F.Paste")
			(net 1 "GND")
			(pinfunction "VSSADPHY")
			(pintype "passive")
		)
		(pad "C7" smd circle
			(at -1.2 -4.4 180)
			(size 0.45 0.45)
			(layers "F.Cu" "F.Mask" "F.Paste")
			(net 11 "/FPGA Power/VCC_DPHY")
			(pinfunction "VCCDPHY1")
			(pintype "power_in")
		)
		(pad "C8" smd circle
			(at -0.4 -4.4 180)
			(size 0.45 0.45)
			(layers "F.Cu" "F.Mask" "F.Paste")
			(net 12 "/FPGA Power/VCC_ADPHY")
			(pinfunction "VCCADPHY1")
			(pintype "power_in")
		)
		(pad "C9" smd circle
			(at 0.4 -4.4 180)
			(size 0.45 0.45)
			(layers "F.Cu" "F.Mask" "F.Paste")
			(net 1 "GND")
			(pinfunction "VSS")
			(pintype "passive")
		)
		(pad "C10" smd circle
			(at 1.2 -4.4 180)
			(size 0.45 0.45)
			(layers "F.Cu" "F.Mask" "F.Paste")
			(net 1 "GND")
			(pinfunction "VSS")
			(pintype "power_in")
		)
		(pad "C11" smd circle
			(at 2 -4.4 180)
			(size 0.45 0.45)
			(layers "F.Cu" "F.Mask" "F.Paste")
			(net 1 "GND")
			(pinfunction "SD0_REXT")
			(pintype "input")
		)
		(pad "C12" smd circle
			(at 2.8 -4.4 180)
			(size 0.45 0.45)
			(layers "F.Cu" "F.Mask" "F.Paste")
			(net 36 "/FPGA/PROGRAMN")
			(pinfunction "PT74B/PROGRAMN")
			(pintype "bidirectional")
		)
		(pad "C13" smd circle
			(at 3.6 -4.4 180)
			(size 0.45 0.45)
			(layers "F.Cu" "F.Mask" "F.Paste")
			(net 389 "unconnected-(U11A-PT82B{slash}MCSNO{slash}MSDO-PadC13)")
			(pinfunction "PT82B/MCSNO/MSDO")
			(pintype "bidirectional+no_connect")
		)
		(pad "C14" smd circle
			(at 4.4 -4.4 180)
			(size 0.45 0.45)
			(layers "F.Cu" "F.Mask" "F.Paste")
			(net 37 "/FPGA/SPI_DQ0_MOSI")
			(pinfunction "PT78B/MOSI/MD0")
			(pintype "bidirectional")
		)
		(pad "C15" smd circle
			(at 5.2 -4.4 180)
			(size 0.45 0.45)
			(layers "F.Cu" "F.Mask" "F.Paste")
			(net 41 "/FPGA/~{FLASH_CS}")
			(pinfunction "PT78A/MCSN/PCLKT0_1")
			(pintype "bidirectional")
		)
		(pad "C16" smd circle
			(at 6 -4.4 180)
			(size 0.45 0.45)
			(layers "F.Cu" "F.Mask" "F.Paste")
			(net 39 "/FPGA/SPI_CLK")
			(pinfunction "PT76A/MCLK/PCLKT0_0")
			(pintype "bidirectional")
		)
		(pad "D1" smd circle
			(at -6 -3.6 180)
			(size 0.45 0.45)
			(layers "F.Cu" "F.Mask" "F.Paste")
			(net 77 "/Peripherals/MIPI0_CLK_P")
			(pinfunction "DPHY0_CK+")
			(pintype "bidirectional")
		)
		(pad "D2" smd circle
			(at -5.2 -3.6 180)
			(size 0.45 0.45)
			(layers "F.Cu" "F.Mask" "F.Paste")
			(net 76 "/Peripherals/MIPI0_CLK_N")
			(pinfunction "DPHY0_CK-")
			(pintype "bidirectional")
		)
		(pad "D3" smd circle
			(at -4.4 -3.6 180)
			(size 0.45 0.45)
			(layers "F.Cu" "F.Mask" "F.Paste")
			(net 1 "GND")
			(pinfunction "VSSADPHY")
			(pintype "passive")
		)
		(pad "D4" smd circle
			(at -3.6 -3.6 180)
			(size 0.45 0.45)
			(layers "F.Cu" "F.Mask" "F.Paste")
			(net 175 "/SDI/RESET_TRST")
			(pinfunction "PL3A/ULC_GPLL0T_IN")
			(pintype "bidirectional")
		)
		(pad "D5" smd circle
			(at -2.8 -3.6 180)
			(size 0.45 0.45)
			(layers "F.Cu" "F.Mask" "F.Paste")
			(net 206 "/SDI/SDI_D14")
			(pinfunction "PL3B/ULC_GPLL0C_IN")
			(pintype "bidirectional")
		)
		(pad "D6" smd circle
			(at -2 -3.6 180)
			(size 0.45 0.45)
			(layers "F.Cu" "F.Mask" "F.Paste")
			(net 177 "/SDI/SW_EN")
			(pinfunction "PL4A")
			(pintype "bidirectional")
		)
		(pad "D7" smd circle
			(at -1.2 -3.6 180)
			(size 0.45 0.45)
			(layers "F.Cu" "F.Mask" "F.Paste")
			(net 4 "1V0_Power")
			(pinfunction "VCC")
			(pintype "power_in")
		)
		(pad "D8" smd circle
			(at -0.4 -3.6 180)
			(size 0.45 0.45)
			(layers "F.Cu" "F.Mask" "F.Paste")
			(net 1 "GND")
			(pinfunction "VSS")
			(pintype "passive")
		)
		(pad "D9" smd circle
			(at 0.4 -3.6 180)
			(size 0.45 0.45)
			(layers "F.Cu" "F.Mask" "F.Paste")
			(net 4 "1V0_Power")
			(pinfunction "VCC")
			(pintype "passive")
		)
		(pad "D10" smd circle
			(at 1.2 -3.6 180)
			(size 0.45 0.45)
			(layers "F.Cu" "F.Mask" "F.Paste")
			(net 173 "JTAG_EN")
			(pinfunction "JTAG_EN")
			(pintype "input")
		)
		(pad "D11" smd circle
			(at 2 -3.6 180)
			(size 0.45 0.45)
			(layers "F.Cu" "F.Mask" "F.Paste")
			(net 15 "/FPGA/INITN")
			(pinfunction "PT74A/INITN\n")
			(pintype "bidirectional")
		)
		(pad "D12" smd circle
			(at 2.8 -3.6 180)
			(size 0.45 0.45)
			(layers "F.Cu" "F.Mask" "F.Paste")
			(net 27 "/FPGA/SPI_DQ3")
			(pinfunction "PT82A/MD3")
			(pintype "bidirectional")
		)
		(pad "D13" smd circle
			(at 3.6 -3.6 180)
			(size 0.45 0.45)
			(layers "F.Cu" "F.Mask" "F.Paste")
			(net 2 "+3V3")
			(pinfunction "VCCIO0")
			(pintype "power_in")
		)
		(pad "D14" smd circle
			(at 4.4 -3.6 180)
			(size 0.45 0.45)
			(layers "F.Cu" "F.Mask" "F.Paste")
			(net 1 "GND")
			(pinfunction "VSS")
			(pintype "passive")
		)
		(pad "D15" smd circle
			(at 5.2 -3.6 180)
			(size 0.45 0.45)
			(layers "F.Cu" "F.Mask" "F.Paste")
			(net 28 "/FPGA/SPI_DQ2")
			(pinfunction "PT80B/MD2")
			(pintype "bidirectional")
		)
		(pad "D16" smd circle
			(at 6 -3.6 180)
			(size 0.45 0.45)
			(layers "F.Cu" "F.Mask" "F.Paste")
			(net 38 "/FPGA/SPI_DQ1_MISO")
			(pinfunction "PT80A/MISO/MD1")
			(pintype "bidirectional")
		)
		(pad "E1" smd circle
			(at -6 -2.8 180)
			(size 0.45 0.45)
			(layers "F.Cu" "F.Mask" "F.Paste")
			(net 75 "/Peripherals/MIPI0_D0_P")
			(pinfunction "DPHY0_D0+")
			(pintype "bidirectional")
		)
		(pad "E2" smd circle
			(at -5.2 -2.8 180)
			(size 0.45 0.45)
			(layers "F.Cu" "F.Mask" "F.Paste")
			(net 74 "/Peripherals/MIPI0_D0_N")
			(pinfunction "DPHY0_D0-")
			(pintype "bidirectional")
		)
		(pad "E3" smd circle
			(at -4.4 -2.8 180)
			(size 0.45 0.45)
			(layers "F.Cu" "F.Mask" "F.Paste")
			(net 12 "/FPGA Power/VCC_ADPHY")
			(pinfunction "VCCADPHY0")
			(pintype "power_in")
		)
		(pad "E4" smd circle
			(at -3.6 -2.8 180)
			(size 0.45 0.45)
			(layers "F.Cu" "F.Mask" "F.Paste")
			(net 178 "/SDI/~{CS_TMS}")
			(pinfunction "PL6A")
			(pintype "bidirectional")
		)
		(pad "E5" smd circle
			(at -2.8 -2.8 180)
			(size 0.45 0.45)
			(layers "F.Cu" "F.Mask" "F.Paste")
			(net 179 "/SDI/SCLK_TCK")
			(pinfunction "PL6B")
			(pintype "bidirectional")
		)
		(pad "E6" smd circle
			(at -2 -2.8 180)
			(size 0.45 0.45)
			(layers "F.Cu" "F.Mask" "F.Paste")
			(net 215 "/SDI/SDI_D17")
			(pinfunction "PL4B")
			(pintype "bidirectional")
		)
		(pad "E7" smd circle
			(at -1.2 -2.8 180)
			(size 0.45 0.45)
			(layers "F.Cu" "F.Mask" "F.Paste")
			(net 1 "GND")
			(pinfunction "VSS")
			(pintype "passive")
		)
		(pad "E8" smd circle
			(at -0.4 -2.8 180)
			(size 0.45 0.45)
			(layers "F.Cu" "F.Mask" "F.Paste")
			(net 1 "GND")
			(pinfunction "VSS")
			(pintype "passive")
		)
		(pad "E9" smd circle
			(at 0.4 -2.8 180)
			(size 0.45 0.45)
			(layers "F.Cu" "F.Mask" "F.Paste")
			(net 107 "/Peripherals/FFC2_RESET")
			(pinfunction "PR4A")
			(pintype "bidirectional")
		)
		(pad "E10" smd circle
			(at 1.2 -2.8 180)
			(size 0.45 0.45)
			(layers "F.Cu" "F.Mask" "F.Paste")
			(net 106 "/Peripherals/FFC2_VSYNC1")
			(pinfunction "PR4B")
			(pintype "bidirectional")
		)
		(pad "E11" smd circle
			(at 2 -2.8 180)
			(size 0.45 0.45)
			(layers "F.Cu" "F.Mask" "F.Paste")
			(net 169 "TMS")
			(pinfunction "PR6B/TMS/SCSN")
			(pintype "bidirectional")
		)
		(pad "E12" smd circle
			(at 2.8 -2.8 180)
			(size 0.45 0.45)
			(layers "F.Cu" "F.Mask" "F.Paste")
			(net 307 "/Peripherals/FFC1_PEN")
			(pinfunction "PR6A")
			(pintype "bidirectional")
		)
		(pad "E13" smd circle
			(at 3.6 -2.8 180)
			(size 0.45 0.45)
			(layers "F.Cu" "F.Mask" "F.Paste")
			(net 99 "/Peripherals/FCC2_SDA2")
			(pinfunction "PR10A")
			(pintype "bidirectional")
		)
		(pad "E14" smd circle
			(at 4.4 -2.8 180)
			(size 0.45 0.45)
			(layers "F.Cu" "F.Mask" "F.Paste")
			(net 171 "TDO")
			(pinfunction "PR10B/TDO/SSO")
			(pintype "bidirectional")
		)
		(pad "E15" smd circle
			(at 5.2 -2.8 180)
			(size 0.45 0.45)
			(layers "F.Cu" "F.Mask" "F.Paste")
			(net 35 "LED0")
			(pinfunction "PT84A")
			(pintype "bidirectional")
		)
		(pad "E16" smd circle
			(at 6 -2.8 180)
			(size 0.45 0.45)
			(layers "F.Cu" "F.Mask" "F.Paste")
			(net 34 "LED1")
			(pinfunction "PT84B")
			(pintype "bidirectional")
		)
		(pad "F1" smd circle
			(at -6 -2 180)
			(size 0.45 0.45)
			(layers "F.Cu" "F.Mask" "F.Paste")
			(net 71 "/Peripherals/MIPI0_D2_P")
			(pinfunction "DPHY0_D2+")
			(pintype "bidirectional")
		)
	)
)
